(kicad_pcb
	(version 20260206)
	(generator "pcbnew")
	(generator_version "10.0")
	(general
		(thickness 1.6)
		(legacy_teardrops no)
	)
	(paper "A4")
	(title_block
		(title "v1-chassis-manager — T6M_CM_d_v01_1031_1645.brd")
		(comment 1 "Open CloudServer (Microsoft) / footprints 919-924 of 2512")
	)
	(layers
		(0 "F.Cu" signal "TOP")
		(4 "In1.Cu" signal "GND1")
		(6 "In2.Cu" signal "IN1")
		(8 "In3.Cu" signal "VCC1")
		(10 "In4.Cu" signal "VCC2")
		(12 "In5.Cu" signal "GND2")
		(14 "In6.Cu" signal "IN2")
		(16 "In7.Cu" signal "IN3")
		(18 "In8.Cu" signal "GND3")
		(2 "B.Cu" signal "BOTTOM")
		(9 "F.Adhes" user "F.Adhesive")
		(11 "B.Adhes" user "B.Adhesive")
		(13 "F.Paste" user "Package Geometry/Pastemask Top")
		(15 "B.Paste" user "Package Geometry/Pastemask Bottom")
		(5 "F.SilkS" user "Ref Des/Silkscreen Top")
		(7 "B.SilkS" user "Ref Des/Silkscreen Bottom")
		(1 "F.Mask" user "Board Geometry/Soldermask Top")
		(3 "B.Mask" user "Board Geometry/Soldermask Bottom")
		(17 "Dwgs.User" user "User.Drawings")
		(19 "Cmts.User" user "User.Comments")
		(21 "Eco1.User" user "User.Eco1")
		(23 "Eco2.User" user "User.Eco2")
		(25 "Edge.Cuts" user "Board Geometry/Outline")
		(27 "Margin" user)
		(31 "F.CrtYd" user "Package Geometry/Place Bound Top")
		(29 "B.CrtYd" user "Package Geometry/Place Bound Bottom")
		(35 "F.Fab" user "Ref Des/Assembly Top")
		(33 "B.Fab" user "Ref Des/Assembly Bottom")
	)
	(footprint ""
		(layer "F.Cu")
		(at 150.47976 -188.126624 90)
		(property "Reference" "C747"
			(at 5.519674 -2.808732 90)
			(unlocked yes)
			(layer "F.SilkS")
			(effects
				(font
					(size 0.7874 0.5842)
					(thickness 0.1524)
				)
				(justify left)
			)
		)
		(property "Value" ""
			(at 0 0 90)
			(layer "F.Fab")
			(effects
				(font
					(size 1.27 1.27)
				)
			)
		)
		(duplicate_pad_numbers_are_jumpers no)
		(fp_line
			(start 0.7874 -0.4064)
			(end 0.7874 0.4064)
			(stroke
				(width 0.1524)
				(type default)
			)
			(layer "F.SilkS")
		)
		(fp_line
			(start -0.7874 -0.4064)
			(end 0.7874 -0.4064)
			(stroke
				(width 0.1524)
				(type default)
			)
			(layer "F.SilkS")
		)
		(fp_line
			(start 0 0.381)
			(end 0 -0.381)
			(stroke
				(width 0.1524)
				(type default)
			)
			(layer "F.SilkS")
		)
		(fp_line
			(start 0.7874 0.4064)
			(end -0.7874 0.4064)
			(stroke
				(width 0.1524)
				(type default)
			)
			(layer "F.SilkS")
		)
		(fp_line
			(start -0.7874 0.4064)
			(end -0.7874 -0.4064)
			(stroke
				(width 0.1524)
				(type default)
			)
			(layer "F.SilkS")
		)
		(fp_poly
			(pts
				(xy -0.5334 0.254) (xy -0.635 0.254) (xy -0.635 0.2286) (xy -0.635 -0.254) (xy -0.5334 -0.254) (xy -0.5334 -0.2794)
				(xy 0.5334 -0.2794) (xy 0.5334 -0.254) (xy 0.635 -0.254) (xy 0.635 0.254) (xy 0.5334 0.254) (xy 0.5334 0.2794)
				(xy -0.508 0.2794) (xy -0.5334 0.2794)
			)
			(stroke
				(width 0)
				(type default)
			)
			(fill no)
			(layer "F.CrtYd")
		)
		(pad "1" smd rect
			(at 0.40005 0 90)
			(size 0.4572 0.508)
			(layers "F.Cu" "F.Mask" "F.Paste")
			(net "UART_T12_NODE1_TXD_R")
		)
		(pad "2" smd rect
			(at -0.40005 0 90)
			(size 0.4572 0.508)
			(layers "F.Cu" "F.Mask" "F.Paste")
			(net "GND")
		)
	)
	(footprint ""
		(layer "F.Cu")
		(at 40.122602 -162.187382 90)
		(property "Reference" "R559"
			(at -1.312672 -1.041654 90)
			(unlocked yes)
			(layer "F.SilkS")
			(effects
				(font
					(size 0.7874 0.5842)
					(thickness 0.1524)
				)
				(justify left)
			)
		)
		(property "Value" ""
			(at 0 0 90)
			(layer "F.Fab")
			(effects
				(font
					(size 1.27 1.27)
				)
			)
		)
		(duplicate_pad_numbers_are_jumpers no)
		(fp_line
			(start 0.7874 -0.4064)
			(end 0.7874 0.4064)
			(stroke
				(width 0.1524)
				(type default)
			)
			(layer "F.SilkS")
		)
		(fp_line
			(start -0.7874 -0.4064)
			(end 0.7874 -0.4064)
			(stroke
				(width 0.1524)
				(type default)
			)
			(layer "F.SilkS")
		)
		(fp_line
			(start 0.7874 0.4064)
			(end -0.7874 0.4064)
			(stroke
				(width 0.1524)
				(type default)
			)
			(layer "F.SilkS")
		)
		(fp_line
			(start -0.7874 0.4064)
			(end -0.7874 -0.4064)
			(stroke
				(width 0.1524)
				(type default)
			)
			(layer "F.SilkS")
		)
		(fp_poly
			(pts
				(xy -0.508 0.2794) (xy -0.508 0.2286) (xy -0.635 0.2286) (xy -0.635 -0.254) (xy -0.5334 -0.254)
				(xy -0.5334 -0.2794) (xy 0.5334 -0.2794) (xy 0.5334 -0.254) (xy 0.635 -0.254) (xy 0.635 0.254) (xy 0.5334 0.254)
				(xy 0.5334 0.2794)
			)
			(stroke
				(width 0)
				(type default)
			)
			(fill no)
			(layer "F.CrtYd")
		)
		(pad "1" smd rect
			(at 0.40005 0 90)
			(size 0.4572 0.508)
			(layers "F.Cu" "F.Mask" "F.Paste")
			(net "GND")
		)
		(pad "2" smd rect
			(at -0.40005 0 90)
			(size 0.4572 0.508)
			(layers "F.Cu" "F.Mask" "F.Paste")
			(net "LAN1_RST")
		)
	)
	(footprint ""
		(layer "F.Cu")
		(at 102.34168 -154.7749 180)
		(property "Reference" "PU4"
			(at -2.512314 -0.688848 90)
			(unlocked yes)
			(layer "F.SilkS")
			(effects
				(font
					(size 0.635 0.4064)
					(thickness 0.1524)
				)
				(justify left)
			)
		)
		(property "Value" ""
			(at 0 0 180)
			(layer "F.Fab")
			(effects
				(font
					(size 1.27 1.27)
				)
			)
		)
		(duplicate_pad_numbers_are_jumpers no)
		(fp_line
			(start 2.055622 0.25019)
			(end 2.563622 0.25019)
			(stroke
				(width 0.1524)
				(type default)
			)
			(layer "F.SilkS")
		)
		(fp_line
			(start 1.575054 1.575054)
			(end 1.575054 1.143)
			(stroke
				(width 0.1524)
				(type default)
			)
			(layer "F.SilkS")
		)
		(fp_line
			(start 1.575054 -1.0668)
			(end 1.575054 -1.575054)
			(stroke
				(width 0.1524)
				(type default)
			)
			(layer "F.SilkS")
		)
		(fp_line
			(start 1.575054 -1.575054)
			(end 1.0414 -1.575054)
			(stroke
				(width 0.1524)
				(type default)
			)
			(layer "F.SilkS")
		)
		(fp_line
			(start 1.0414 1.575054)
			(end 1.575054 1.575054)
			(stroke
				(width 0.1524)
				(type default)
			)
			(layer "F.SilkS")
		)
		(fp_line
			(start -0.255778 -2.350262)
			(end -0.255778 -2.045462)
			(stroke
				(width 0.1524)
				(type default)
			)
			(layer "F.SilkS")
		)
		(fp_line
			(start -0.750062 2.043938)
			(end -0.750062 2.348738)
			(stroke
				(width 0.1524)
				(type default)
			)
			(layer "F.SilkS")
		)
		(fp_line
			(start -1.0668 -1.575054)
			(end -1.575054 -1.575054)
			(stroke
				(width 0.1524)
				(type default)
			)
			(layer "F.SilkS")
		)
		(fp_line
			(start -1.575054 1.575054)
			(end -1.0922 1.575054)
			(stroke
				(width 0.1524)
				(type default)
			)
			(layer "F.SilkS")
		)
		(fp_line
			(start -1.575054 1.0922)
			(end -1.575054 1.575054)
			(stroke
				(width 0.1524)
				(type default)
			)
			(layer "F.SilkS")
		)
		(fp_line
			(start -1.575054 -1.575054)
			(end -1.575054 -1.0414)
			(stroke
				(width 0.1524)
				(type default)
			)
			(layer "F.SilkS")
		)
		(fp_poly
			(pts
				(xy -1.687576 -0.998474) (xy -2.22504 -2.073148) (xy -2.76225 -1.535938)
			)
			(stroke
				(width 0)
				(type default)
			)
			(fill yes)
			(layer "F.SilkS")
		)
		(fp_poly
			(pts
				(xy -1.575054 1.575054) (xy -0.9398 1.575054) (xy -0.9398 1.9558) (xy 0.9398 1.9558) (xy 0.9398 1.575054)
				(xy 1.575054 1.575054) (xy 1.575054 0.9398) (xy 1.9558 0.9398) (xy 1.9558 -0.9398) (xy 1.575054 -0.9398)
				(xy 1.575054 -1.575054) (xy 0.9398 -1.575054) (xy 0.9398 -1.9558) (xy -0.9398 -1.9558) (xy -0.9398 -1.575054)
				(xy -1.575054 -1.575054) (xy -1.575054 -0.9398) (xy -1.9558 -0.9398) (xy -1.9558 0.9398) (xy -1.575054 0.9398)
			)
			(stroke
				(width 0)
				(type default)
			)
			(fill no)
			(layer "F.CrtYd")
		)
		(fp_line
			(start 2.055622 0.25019)
			(end 2.563622 0.25019)
			(stroke
				(width 0.1)
				(type default)
			)
			(layer "F.Fab")
		)
		(fp_line
			(start 1.575054 1.575054)
			(end -1.575054 1.575054)
			(stroke
				(width 0.1)
				(type default)
			)
			(layer "F.Fab")
		)
		(fp_line
			(start 1.575054 -1.575054)
			(end 1.575054 1.575054)
			(stroke
				(width 0.1)
				(type default)
			)
			(layer "F.Fab")
		)
		(fp_line
			(start -0.255778 -2.350262)
			(end -0.255778 -2.045462)
			(stroke
				(width 0.1)
				(type default)
			)
			(layer "F.Fab")
		)
		(fp_line
			(start -0.750062 2.043938)
			(end -0.750062 2.348738)
			(stroke
				(width 0.1)
				(type default)
			)
			(layer "F.Fab")
		)
		(fp_line
			(start -1.575054 1.575054)
			(end -1.575054 -1.575054)
			(stroke
				(width 0.1)
				(type default)
			)
			(layer "F.Fab")
		)
		(fp_line
			(start -1.575054 -1.575054)
			(end 1.575054 -1.575054)
			(stroke
				(width 0.1)
				(type default)
			)
			(layer "F.Fab")
		)
		(fp_poly
			(pts
				(xy -2.100072 -0.750062) (xy -3.240024 -1.130046) (xy -3.240024 -0.370078)
			)
			(stroke
				(width 0)
				(type default)
			)
			(fill yes)
			(layer "F.Fab")
		)
		(fp_text user "12"
			(at 2.65049 -1.886458 0)
			(unlocked yes)
			(layer "F.SilkS")
			(effects
				(font
					(size 0.635 0.4064)
					(thickness 0.1524)
				)
				(justify left)
			)
		)
		(fp_text user "9"
			(at 2.144014 1.3335 0)
			(unlocked yes)
			(layer "F.SilkS")
			(effects
				(font
					(size 0.635 0.4064)
					(thickness 0.1524)
				)
				(justify left)
			)
		)
		(fp_text user "16"
			(at -0.864362 -2.029206 0)
			(unlocked yes)
			(layer "F.SilkS")
			(effects
				(font
					(size 0.635 0.4064)
					(thickness 0.1524)
				)
				(justify left)
			)
		)
		(fp_text user "5"
			(at -0.979424 2.084578 0)
			(unlocked yes)
			(layer "F.SilkS")
			(effects
				(font
					(size 0.635 0.4064)
					(thickness 0.1524)
				)
				(justify left)
			)
		)
		(fp_text user "9"
			(at 1.767586 1.584325 180)
			(unlocked yes)
			(layer "F.Fab")
			(effects
				(font
					(size 0.78994 0.579882)
					(thickness 0.000001)
				)
				(justify left)
			)
		)
		(fp_text user "12"
			(at 1.708912 -1.514475 180)
			(unlocked yes)
			(layer "F.Fab")
			(effects
				(font
					(size 0.78994 0.579882)
					(thickness 0.000001)
				)
				(justify left)
			)
		)
		(fp_text user "5"
			(at -1.737868 2.295525 180)
			(unlocked yes)
			(layer "F.Fab")
			(effects
				(font
					(size 0.78994 0.579882)
					(thickness 0.000001)
				)
				(justify left)
			)
		)
		(fp_text user "16"
			(at -2.457958 -2.225675 180)
			(unlocked yes)
			(layer "F.Fab")
			(effects
				(font
					(size 0.78994 0.579882)
					(thickness 0.000001)
				)
				(justify left)
			)
		)
		(pad "1" smd rect
			(at -1.474978 -0.750062 270)
			(size 0.254 0.8382)
			(layers "F.Cu" "F.Mask" "F.Paste")
			(net "P1V8_STB_NODE1_FB")
		)
		(pad "2" smd rect
			(at -1.474978 -0.249936 270)
			(size 0.254 0.8382)
			(layers "F.Cu" "F.Mask" "F.Paste")
			(net "P1V8_STB_NODE1_VREG5")
		)
		(pad "3" smd rect
			(at -1.474978 0.249936 270)
			(size 0.254 0.8382)
			(layers "F.Cu" "F.Mask" "F.Paste")
			(net "P1V8_STB_NODE1_SS")
		)
		(pad "4" smd rect
			(at -1.474978 0.750062 270)
			(size 0.254 0.8382)
			(layers "F.Cu" "F.Mask" "F.Paste")
			(net "GND")
		)
		(pad "5" smd rect
			(at -0.750062 1.474978 180)
			(size 0.254 0.8382)
			(layers "F.Cu" "F.Mask" "F.Paste")
			(net "PWRGD_NODE1_P1V8_STB_PG")
		)
		(pad "6" smd rect
			(at -0.249936 1.474978 180)
			(size 0.254 0.8382)
			(layers "F.Cu" "F.Mask" "F.Paste")
			(net "FM_CPLD_NODE1_P1V8_STB_S_EN")
		)
		(pad "7" smd rect
			(at 0.249936 1.474978 180)
			(size 0.254 0.8382)
			(layers "F.Cu" "F.Mask" "F.Paste")
			(net "GND")
		)
		(pad "8" smd rect
			(at 0.750062 1.474978 180)
			(size 0.254 0.8382)
			(layers "F.Cu" "F.Mask" "F.Paste")
			(net "GND")
		)
		(pad "9" smd rect
			(at 1.474978 0.750062 270)
			(size 0.254 0.8382)
			(layers "F.Cu" "F.Mask" "F.Paste")
			(net "SW_P1V8_STB_NODE1_PH")
		)
		(pad "10" smd rect
			(at 1.474978 0.249936 270)
			(size 0.254 0.8382)
			(layers "F.Cu" "F.Mask" "F.Paste")
			(net "SW_P1V8_STB_NODE1_PH")
		)
		(pad "11" smd rect
			(at 1.474978 -0.249936 270)
			(size 0.254 0.8382)
			(layers "F.Cu" "F.Mask" "F.Paste")
			(net "SW_P1V8_STB_NODE1_PH")
		)
		(pad "12" smd rect
			(at 1.474978 -0.750062 270)
			(size 0.254 0.8382)
			(layers "F.Cu" "F.Mask" "F.Paste")
			(net "SW_P1V8_STB_NODE1_BT")
		)
		(pad "13" smd rect
			(at 0.750062 -1.474978 180)
			(size 0.254 0.8382)
			(layers "F.Cu" "F.Mask" "F.Paste")
			(net "P12V_AUX")
		)
		(pad "14" smd rect
			(at 0.249936 -1.474978 180)
			(size 0.254 0.8382)
			(layers "F.Cu" "F.Mask" "F.Paste")
			(net "P12V_AUX")
		)
		(pad "15" smd rect
			(at -0.249936 -1.474978 180)
			(size 0.254 0.8382)
			(layers "F.Cu" "F.Mask" "F.Paste")
			(net "P5V_STB_NODE1")
		)
		(pad "16" smd rect
			(at -0.750062 -1.474978 180)
			(size 0.254 0.8382)
			(layers "F.Cu" "F.Mask" "F.Paste")
			(net "P1V8_STB_NODE1")
		)
		(pad "TH" smd rect
			(at 0 0 270)
			(size 1.7018 1.7018)
			(layers "F.Cu" "F.Mask" "F.Paste")
			(net "GND")
		)
		(zone
			(layer "F.Cu")
			(hatch none 0.5)
			(connect_pads
				(clearance 0)
			)
			(min_thickness 0.25)
			(keepout
				(tracks not_allowed)
				(vias allowed)
				(pads allowed)
				(copperpour not_allowed)
				(footprints allowed)
			)
			(placement
				(enabled no)
				(sheetname "")
			)
			(fill
				(thermal_gap 0.5)
				(thermal_bridge_width 0.5)
				(island_removal_mode 0)
			)
			(polygon
				(pts
					(xy 103.33228 -153.7843) (xy 101.35108 -153.7843) (xy 101.35108 -155.7655) (xy 101.42728 -155.7655)
					(xy 101.42728 -155.6893) (xy 101.42728 -153.8605) (xy 103.25608 -153.8605) (xy 103.25608 -155.6639)
					(xy 103.33228 -155.6639)
				)
			)
		)
		(zone
			(layer "F.Cu")
			(hatch none 0.5)
			(connect_pads
				(clearance 0)
			)
			(min_thickness 0.25)
			(keepout
				(tracks allowed)
				(vias not_allowed)
				(pads allowed)
				(copperpour not_allowed)
				(footprints allowed)
			)
			(placement
				(enabled no)
				(sheetname "")
			)
			(fill
				(thermal_gap 0.5)
				(thermal_bridge_width 0.5)
				(island_removal_mode 0)
			)
			(polygon
				(pts
					(xy 103.33228 -153.7843) (xy 101.35108 -153.7843) (xy 101.35108 -155.7655) (xy 103.33228 -155.7655)
					(xy 103.33228 -155.6893) (xy 101.42728 -155.6893) (xy 101.42728 -153.8605) (xy 103.25608 -153.8605)
					(xy 103.25608 -155.6639) (xy 103.33228 -155.6639)
				)
			)
		)
	)
	(footprint ""
		(layer "F.Cu")
		(at 74.458068 -94.131892 -90)
		(property "Reference" "R154"
			(at 55.53329 -24.083264 90)
			(unlocked yes)
			(layer "F.SilkS")
			(effects
				(font
					(size 0.7874 0.5842)
					(thickness 0.1524)
				)
				(justify left)
			)
		)
		(property "Value" ""
			(at 0 0 270)
			(layer "F.Fab")
			(effects
				(font
					(size 1.27 1.27)
				)
			)
		)
		(duplicate_pad_numbers_are_jumpers no)
		(fp_line
			(start -0.7874 0.4064)
			(end -0.7874 -0.4064)
			(stroke
				(width 0.1524)
				(type default)
			)
			(layer "F.SilkS")
		)
		(fp_line
			(start 0.7874 0.4064)
			(end -0.7874 0.4064)
			(stroke
				(width 0.1524)
				(type default)
			)
			(layer "F.SilkS")
		)
		(fp_line
			(start -0.7874 -0.4064)
			(end 0.7874 -0.4064)
			(stroke
				(width 0.1524)
				(type default)
			)
			(layer "F.SilkS")
		)
		(fp_line
			(start 0.7874 -0.4064)
			(end 0.7874 0.4064)
			(stroke
				(width 0.1524)
				(type default)
			)
			(layer "F.SilkS")
		)
		(fp_poly
			(pts
				(xy -0.508 0.2794) (xy -0.508 0.2286) (xy -0.635 0.2286) (xy -0.635 -0.254) (xy -0.5334 -0.254)
				(xy -0.5334 -0.2794) (xy 0.5334 -0.2794) (xy 0.5334 -0.254) (xy 0.635 -0.254) (xy 0.635 0.254) (xy 0.5334 0.254)
				(xy 0.5334 0.2794)
			)
			(stroke
				(width 0)
				(type default)
			)
			(fill no)
			(layer "F.CrtYd")
		)
		(pad "1" smd rect
			(at 0.40005 0 270)
			(size 0.4572 0.508)
			(layers "F.Cu" "F.Mask" "F.Paste")
			(net "PD_CPU_NODE1_BOOTDEVSEL")
		)
		(pad "2" smd rect
			(at -0.40005 0 270)
			(size 0.4572 0.508)
			(layers "F.Cu" "F.Mask" "F.Paste")
			(net "GND")
		)
	)
	(footprint ""
		(layer "F.Cu")
		(at 88.43518 -84.118704 180)
		(property "Reference" "C813"
			(at 2.10566 1.588008 0)
			(unlocked yes)
			(layer "F.SilkS")
			(effects
				(font
					(size 0.7874 0.5842)
					(thickness 0.1524)
				)
				(justify left)
			)
		)
		(property "Value" ""
			(at 0 0 180)
			(layer "F.Fab")
			(effects
				(font
					(size 1.27 1.27)
				)
			)
		)
		(duplicate_pad_numbers_are_jumpers no)
		(fp_line
			(start 1.905 0.8636)
			(end -1.905 0.8636)
			(stroke
				(width 0.1524)
				(type default)
			)
			(layer "F.SilkS")
		)
		(fp_line
			(start 1.905 -0.8636)
			(end 1.905 0.8636)
			(stroke
				(width 0.1524)
				(type default)
			)
			(layer "F.SilkS")
		)
		(fp_line
			(start 0 0.8382)
			(end 0 -0.8382)
			(stroke
				(width 0.1524)
				(type default)
			)
			(layer "F.SilkS")
		)
		(fp_line
			(start -1.905 0.8636)
			(end -1.905 -0.8636)
			(stroke
				(width 0.1524)
				(type default)
			)
			(layer "F.SilkS")
		)
		(fp_line
			(start -1.905 -0.8636)
			(end 1.905 -0.8636)
			(stroke
				(width 0.1524)
				(type default)
			)
			(layer "F.SilkS")
		)
		(fp_rect
			(start -1.524 0.7366)
			(end 1.524 -0.7366)
			(stroke
				(width 0)
				(type default)
			)
			(fill no)
			(layer "F.CrtYd")
		)
		(pad "1" smd rect
			(at 0.94996 0 180)
			(size 1.1176 1.3716)
			(layers "F.Cu" "F.Mask" "F.Paste")
			(net "P1V05_SUS_NODE1")
		)
		(pad "2" smd rect
			(at -0.94996 0 180)
			(size 1.1176 1.3716)
			(layers "F.Cu" "F.Mask" "F.Paste")
			(net "GND")
		)
	)
	(footprint ""
		(layer "F.Cu")
		(at 43.686222 -106.475784 -90)
		(property "Reference" "PR5"
			(at 2.327148 3.311144 90)
			(unlocked yes)
			(layer "F.SilkS")
			(effects
				(font
					(size 0.7874 0.5842)
					(thickness 0.1524)
				)
				(justify left)
			)
		)
		(property "Value" ""
			(at 0 0 270)
			(layer "F.Fab")
			(effects
				(font
					(size 1.27 1.27)
				)
			)
		)
		(duplicate_pad_numbers_are_jumpers no)
		(fp_line
			(start -0.7874 0.4064)
			(end -0.7874 -0.4064)
			(stroke
				(width 0.1524)
				(type default)
			)
			(layer "F.SilkS")
		)
		(fp_line
			(start 0.7874 0.4064)
			(end -0.7874 0.4064)
			(stroke
				(width 0.1524)
				(type default)
			)
			(layer "F.SilkS")
		)
		(fp_line
			(start -0.7874 -0.4064)
			(end 0.7874 -0.4064)
			(stroke
				(width 0.1524)
				(type default)
			)
			(layer "F.SilkS")
		)
		(fp_line
			(start 0.7874 -0.4064)
			(end 0.7874 0.4064)
			(stroke
				(width 0.1524)
				(type default)
			)
			(layer "F.SilkS")
		)
		(fp_poly
			(pts
				(xy -0.508 0.2794) (xy -0.508 0.2286) (xy -0.635 0.2286) (xy -0.635 -0.254) (xy -0.5334 -0.254)
				(xy -0.5334 -0.2794) (xy 0.5334 -0.2794) (xy 0.5334 -0.254) (xy 0.635 -0.254) (xy 0.635 0.254) (xy 0.5334 0.254)
				(xy 0.5334 0.2794)
			)
			(stroke
				(width 0)
				(type default)
			)
			(fill no)
			(layer "F.CrtYd")
		)
		(pad "1" smd rect
			(at 0.40005 0 270)
			(size 0.4572 0.508)
			(layers "F.Cu" "F.Mask" "F.Paste")
			(net "P3V3_STB_NODE1_VREG5")
		)
		(pad "2" smd rect
			(at -0.40005 0 270)
			(size 0.4572 0.508)
			(layers "F.Cu" "F.Mask" "F.Paste")
			(net "PWRGD_NODE1_P3V3_STB_PG")
		)
	)
)
